# Lightning_M.2_EQL.xlsx — PCIe signal (si-constraints)
| SPEC |  |  |  |  |  |  |
| Length match | 5 mil |  |  |  |  |  |
| NET | L1 | L1 < 4 inch | Length match <1 mil | Length match <300mil | Max Via =2 |  |
| D85_PCIE_A_TX0_P | 1053.4100000000001 | OK | OK | OK | 1 |  |
| D85_PCIE_A_TX0_N | 1053.3499999999999 | OK |  | OK |  |  |
| D85_PCIE_A_TX1_P | 1230.57 | OK | OK | OK | 1 |  |
| D85_PCIE_A_TX1_N | 1230.52 | OK |  | OK |  |  |
| D85_PCIE_B_TX0_P | 505.9 | OK | OK | OK | 1 |  |
| D85_PCIE_B_TX0_N | 505.9 | OK |  | OK |  |  |
| D85_PCIE_B_TX1_P | 536.89 | OK | OK | OK | 1 |  |
| D85_PCIE_B_TX1_N | 536.82000000000005 | OK |  | OK |  |  |
| NET | L1 | L1<3.5 inch | L1 | Length match <1 mil | Length match <300 mil | Max Via =2 |
| D85_PCIE_A_RX0_P | 1141.3 | OK | 1244.6500000000001 | OK | OK | 2 |
| D85_PCIE_A_RX0_N | 1140.7 | OK | 1244.06 |  | OK |  |
| D85_PCIE_A_RX1_P | 1538.32 | OK | 1538.32 | OK | OK | 2 |
| D85_PCIE_A_RX1_N | 1537.67 | OK | 1537.67 |  | OK |  |
| D85_PCIE_B_RX0_P | 947.24 | OK | 947.24 | OK | OK | 2 |
| D85_PCIE_B_RX0_N | 946.63 | OK | 946.63 |  | OK |  |
| D85_PCIE_B_RX1_P | 955.96 | OK | 955.96 | OK | OK | 2 |
| D85_PCIE_B_RX1_N | 955.34 | OK | 955.34 |  | OK |  |
